FILE_TYPE = CONNECTIVITY;
{Allegro Design Entry HDL 16.6-p007 (v16-6-112F) 10/10/2012}
"PAGE_NUMBER" = 155;
0"NC";
1"GND\g";
2"GND\g";
3"P3V3_STBY\g";
4"GND\g";
5"P12V_STBY\g";
6"P5V_STBY\g";
7"P5V_STBY\g";
8"P3V3_STBY\g";
9"GND\g";
10"P3V3_STBY\g";
11"LED_POSTCODE_1_R";
12"FM_UART_SWITCH_N";
13"SPA_SIN_SW_R";
14"SPA_5V_SIN_SW_D";
15"LED_POSTCODE_3_R";
16"LED_POSTCODE_5_R";
17"LED_POSTCODE_7_R";
18"SPA_5V_SIN_SW";
19"LED_POSTCODE_4_R";
20"LED_POSTCODE_2_R";
21"LED_POSTCODE_2";
22"SPA_MID_DBG1_RX";
23"P5V_STBY_DGB_FS"VOLTAGE"5";
24"SPA_MID_DBG1_TX";
25"FM_DEBUG_RST_BTN_N";
26"LED_POSTCODE_0_R";
27"LED_POSTCODE_2_R";
28"LED_POSTCODE_1";
29"FM_CPLD_DBG_PWR_EN";
30"FM_CPLD_DBG_PWR_EN_N";
31"FM_CPLD_DBG_PWR_EN_R_N";
32"P5V_STBY_DBG"VOLTAGE"5";
33"LED_POSTCODE_0";
34"LED_POSTCODE_0_R";
35"LED_POSTCODE_3_R";
36"LED_POSTCODE_5_R";
37"LED_POSTCODE_6_R";
38"LED_POSTCODE_4_R";
39"LED_POSTCODE_6_R";
40"LED_POSTCODE_7_R";
41"LED_POSTCODE_7";
42"LED_POSTCODE_4";
43"LED_POSTCODE_1_R";
44"LED_POSTCODE_6";
45"LED_POSTCODE_5";
46"LED_POSTCODE_3";
%"CAP_A"
"1","(-4100,1050)","0","dev_discrete","I127";
;
LOCATION"C9A1"
VALUE"0.1UF"
MATERIAL"X7R"
VOLTAGE"16V"
PACK_TYPE"0402V"
TOLERANCE"10%"
PART_NUMBER"A36096-030"
BOM_COST"DEBUG"
CDS_SEC"1"
$SEC"1"
ROOM"BMC_DEBUG_HEADER"
CDS_LOCATION"C9A1"
CDS_LIB"dev_discrete";
"B"
$PN"2"1;
"A"
$PN"1"23;
%"GND"
"1","(-4100,825)","0","mstr_symbols","I128";
;
HDL_POWER"GND"
SIZE"1B"
BODY_TYPE"PLUMBING"
CDS_LIB"mstr_symbols"
VOLTAGE"0.0V";
"A\NAC"1;
%"FUSE"
"1","(-4275,2625)","0","mstr_discrete","I129";
;
CDS_SEC"1"
CONFIG"069.50018.0001"
LOCATION"F1L1"
MATERIAL"IC"
PART_NUMBER"H45581-001"
CDS_LIB"mstr_discrete"
PACK_TYPE"SMT"
SEC_TYPE"SMT"
BOM_COST"DEBUG"
SEC"1"
CDS_LOCATION"F1L1"
ROOM"BMC_DEBUG_HEADER";
"A<SIZE-1..0>"
$PN"1"32;
"B<SIZE-1..0>"
$PN"2"23;
%"RES"
"2","(-5950,2575)","0","mstr_discrete","I130";
;
CDS_SEC"1"
LOCATION"R1L9"
WATTAGE"1/16W"
TOLERANCE"1%"
VALUE"100.0K"
MATERIAL"CHIP"
PACK_TYPE"0402"
PART_NUMBER"G21796-010"
BOM_COST"DEBUG"
SEC_TYPE"0402"
SEC"1"
ROOM"BMC_DEBUG_HEADER"
CDS_LOCATION"R1L9"
CDS_LIB"mstr_discrete";
"A"
$PN"1"5;
"B"
$PN"2"29;
%"CONN14_H54902001"
"1","(-4450,1500)","0","mstr_conn","I171";
;
PART_NUMBER"H54902-001"
LOCATION"J9A2"
MATERIAL"CONN"
BOM_COST"DEBUG"
$SEC"1"
PACK_TYPE"PIP"
CDS_SEC"1"
CDS_LOCATION"J9A2"
ROOM"BMC_DEBUG_HEADER"
CDS_LIB"mstr_conn"
CDS_LMAN_SYM_OUTLINE"-250,250,250,-250";
"IO13"
$PN"13"9;
"IO11"
$PN"11"25;
"IO9"
$PN"9"24;
"IO7"
$PN"7"39;
"IO5"
$PN"5"38;
"IO3"
$PN"3"27;
"IO1"
$PN"1"26;
"IO2"
$PN"2"43;
"IO14"
$PN"14"23;
"IO12"
$PN"12"12;
"IO10"
$PN"10"18;
"IO8"
$PN"8"17;
"IO4"
$PN"4"15;
"IO6"
$PN"6"16;
%"TTL1G07_A"
"1","(-2100,1400)","0","mstr_ttl","I178";
;
CDS_SEC"1"
VALUE"74LVC1G07"
MATERIAL"IC"
LOCATION"U9A1"
PART_NUMBER"C88419-001"
POWER_GROUP"VCC=P3V3_STBY;GND=GND"
CDS_LIB"mstr_ttl"
ROOM"BMC_DEBUG_HEADER"
CDS_LOCATION"U9A1"
SEC"1"
SEC_TYPE"SOP"
BOM_COST"DEBUG"
PACK_TYPE"SOP";
"Y"
$PN"4"13;
"A"
$PN"2"14;
%"GND"
"1","(-5950,1800)","0","mstr_symbols","I180";
;
BODY_TYPE"PLUMBING"
VOLTAGE"0.0V"
SIZE"1B"
CDS_LIB"mstr_symbols"
HDL_POWER"GND";
"A\NAC"2;
%"P3V3_STBY"
"1","(-1550,3325)","0","mstr_symbols","I183";
;
SIZE"1B"
CDS_LIB"mstr_symbols"
BODY_TYPE"PLUMBING"
VOLTAGE"3.3V"
HDL_POWER"P3V3_STBY";
"G\NAC"3;
%"CAP_A"
"1","(-1550,3025)","0","dev_discrete","I184";
;
PACK_TYPE"0402V"
PART_NUMBER"A36096-030"
VALUE"0.1UF"
LOCATION"C1T56"
MATERIAL"X7R"
TOLERANCE"10%"
VOLTAGE"16V"
BOM_COST"DEBUG"
SEC_TYPE"0402V"
ROOM"BMC_DEBUG_HEADER"
CDS_SEC"1"
SEC"1"
CDS_LOCATION"C1T56"
CDS_LIB"dev_discrete";
"B"
$PN"2"4;
"A"
$PN"1"3;
%"GND"
"1","(-1550,2725)","0","mstr_symbols","I185";
;
SIZE"1B"
HDL_POWER"GND"
BODY_TYPE"PLUMBING"
CDS_LIB"mstr_symbols"
VOLTAGE"0.0V";
"A\NAC"4;
%"RES"
"1","(-7050,2000)","0","mstr_discrete","I186";
;
LOCATION"R1L2"
PART_NUMBER"G21796-066"
WATTAGE"1/16W"
VALUE"10.0"
TOLERANCE"1%"
PACK_TYPE"0402"
MATERIAL"CHIP"
CDS_LIB"mstr_discrete"
BOM_COST"DEBUG"
CDS_SEC"1"
ROOM"BMC_DEBUG_HEADER"
CDS_LOCATION"R1L2"
$SEC"1";
"B"
$PN"2"31;
"A"
$PN"1"30;
%"FET_N_DUAL"
"5","(-5950,2100)","0","mstr_discrete","I187";
;
CDS_SEC"2"
PART_NUMBER"E40049-001"
MATERIAL"FET"
VALUE"NTJD4001N"
LOCATION"Q1L2"
PACK_TYPE"SMLF"
CDS_LIB"mstr_discrete"
ROOM"BMC"
CDS_LOCATION"Q1L2"
SEC"2"
BOM_COST"BMC_DEBUG_HEADER"
SEC_TYPE"SMLF";
"GATE <SIZE -1..0>"
$PN"5"31;
"SOURCE <SIZE-1..0>"
$PN"4"2;
"DRAIN <SIZE -1..0>"
$PN"3"29;
%"FET_N_DUAL"
"5","(-4950,2625)","1","mstr_discrete","I188";
;
CDS_SEC"1"
LOCATION"Q1L2"
PART_NUMBER"E40049-001"
MATERIAL"FET"
VALUE"NTJD4001N"
BOM_COST"BMC_DEBUG_HEADER"
ROOM"BMC"
PACK_TYPE"SMLF"
CDS_LIB"mstr_discrete"
SEC_TYPE"SMLF"
SEC"1"
CDS_LOCATION"Q1L2";
"GATE <SIZE -1..0>"
$PN"2"29;
"SOURCE <SIZE-1..0>"
$PN"1"32;
"DRAIN <SIZE -1..0>"
$PN"6"7;
%"P12V_STBY"
"1","(-5950,2900)","0","mstr_symbols","I193";
;
CDS_LIB"mstr_symbols"
HDL_POWER"P12V_STBY"
BODY_TYPE"PLUMBING"
SIZE"1B"
VOLTAGE"12.0V";
"G\NAC"5;
%"P5V_STBY"
"1","(-3350,1250)","0","mstr_symbols","I194";
;
HDL_POWER"P5V_STBY"
BODY_TYPE"PLUMBING"
SIZE"1B"
CDS_LIB"mstr_symbols"
VOLTAGE"5.0V";
"G\NAC"6;
%"RES"
"1","(-1950,1775)","0","mstr_discrete","I196";
;
CDS_SEC"1"
CDS_LOCATION"R6W19"
VALUE"0.0"
MATERIAL"CHIP"
TOLERANCE"5%"
POP"NOPOP"
PART_NUMBER"G21497-005"
LOCATION"R6W19"
PACK_TYPE"0402"
WATTAGE"1/16W"
CDS_LIB"mstr_discrete"
ROOM"BMC_DEBUG_HEADER"
BOM_COST"DEBUG"
SEC"1"
SEC_TYPE"0402";
"B"
$PN"2"13;
"A"
$PN"1"14;
%"P5V_STBY"
"1","(-5400,2750)","0","mstr_symbols","I197";
;
SIZE"1B"
VOLTAGE"5.0V"
BODY_TYPE"PLUMBING"
HDL_POWER"P5V_STBY"
CDS_LIB"mstr_symbols";
"G\NAC"7;
%"RES"
"2","(-3350,1050)","0","mstr_discrete","I198";
;
CDS_SEC"1"
TOLERANCE"1%"
VALUE"20.0K"
PART_NUMBER"G21796-040"
WATTAGE"1/16W"
MATERIAL"CHIP"
PACK_TYPE"0402"
LOCATION"R9A5"
CDS_LOCATION"R9A5"
ROOM"SB"
BOM_COST"SB"
CDS_LIB"mstr_discrete"
SEC_TYPE"0402"
SEC"1";
"A"
$PN"1"6;
"B"
$PN"2"12;
%"P3V3_STBY"
"1","(-2700,1950)","0","mstr_symbols","I199";
;
HDL_POWER"P3V3_STBY"
VOLTAGE"3.3V"
CDS_LIB"mstr_symbols"
BODY_TYPE"PLUMBING"
SIZE"1B";
"G\NAC"8;
%"RES"
"2","(-2700,1700)","0","mstr_discrete","I201";
;
CDS_SEC"1"
TOLERANCE"1%"
LOCATION"R6W40"
VALUE"10.0K"
WATTAGE"1/16W"
MATERIAL"CHIP"
PART_NUMBER"G21796-016"
PACK_TYPE"0402"
CDS_LOCATION"R6W40"
ROOM"CPU0"
BOM_COST"PROC_SIDEBAND"
CDS_LIB"mstr_discrete"
SEC_TYPE"0402"
SEC"1";
"A"
$PN"1"8;
"B"
$PN"2"14;
%"DIODE"
"3","(-2900,1400)","0","mstr_discrete","I202";
;
CDS_SEC"1"
CDS_LOCATION"CR9W1"
MATERIAL"IC"
PACK_TYPE"SMLF"
LOCATION"CR9W1"
VALUE"BAT54WS"
PART_NUMBER"C73510-001"
SEC"1"
SEC_TYPE"SMLF"
CDS_LIB"mstr_discrete";
"C"
$PN"1"18;
"A"
$PN"2"14;
%"GND"
"1","(-4825,1125)","0","mstr_symbols","I41";
;
SIZE"1B"
HDL_POWER"GND"
BODY_TYPE"PLUMBING"
CDS_LIB"mstr_symbols"
VOLTAGE"0.0V";
"A\NAC"9;
%"RES"
"1","(-1125,1400)","0","mstr_discrete","I53";
;
CDS_SEC"1"
VALUE"0.0"
WATTAGE"1/16W"
PART_NUMBER"G21497-005"
TOLERANCE"5%"
MATERIAL"CHIP"
PACK_TYPE"0402"
LOCATION"R9A8"
CDS_LOCATION"R9A8"
CDS_LIB"mstr_discrete"
ROOM"BMC_DEBUG_HEADER"
SEC"1"
SEC_TYPE"0402"
BOM_COST"DEBUG";
"B"
$PN"2"22;
"A"
$PN"1"13;
%"RES"
"1","(-6900,4650)","0","mstr_discrete","I65";
;
PACK_TYPE"0402"
MATERIAL"CHIP"
LOCATION"R1L32"
WATTAGE"1/16W"
VALUE"10.0"
TOLERANCE"1%"
PART_NUMBER"G21796-066"
BOM_COST"DEBUG"
CDS_SEC"1"
$SEC"1"
CDS_LOCATION"R1L32"
ROOM"BMC_DEBUG_HEADER"
CDS_LIB"mstr_discrete";
"B"
$PN"2"34;
"A"
$PN"1"33;
%"RES"
"1","(-6900,4500)","0","mstr_discrete","I66";
;
VALUE"10.0"
LOCATION"R1L30"
TOLERANCE"1%"
WATTAGE"1/16W"
PART_NUMBER"G21796-066"
MATERIAL"CHIP"
PACK_TYPE"0402"
CDS_LOCATION"R1L30"
ROOM"BMC_DEBUG_HEADER"
BOM_COST"DEBUG"
CDS_SEC"1"
$SEC"1"
CDS_LIB"mstr_discrete";
"B"
$PN"2"11;
"A"
$PN"1"28;
%"RES"
"1","(-6900,4350)","0","mstr_discrete","I67";
;
LOCATION"R1L25"
WATTAGE"1/16W"
TOLERANCE"1%"
PART_NUMBER"G21796-066"
VALUE"10.0"
PACK_TYPE"0402"
MATERIAL"CHIP"
$SEC"1"
CDS_SEC"1"
CDS_LOCATION"R1L25"
CDS_LIB"mstr_discrete"
ROOM"BMC_DEBUG_HEADER"
BOM_COST"DEBUG";
"B"
$PN"2"20;
"A"
$PN"1"21;
%"RES"
"1","(-6900,4200)","0","mstr_discrete","I68";
;
VALUE"10.0"
PART_NUMBER"G21796-066"
TOLERANCE"1%"
WATTAGE"1/16W"
LOCATION"R1L24"
PACK_TYPE"0402"
MATERIAL"CHIP"
CDS_LOCATION"R1L24"
ROOM"BMC_DEBUG_HEADER"
BOM_COST"DEBUG"
$SEC"1"
CDS_SEC"1"
CDS_LIB"mstr_discrete";
"B"
$PN"2"35;
"A"
$PN"1"46;
%"RES"
"1","(-6900,4050)","0","mstr_discrete","I73";
;
VALUE"10.0"
LOCATION"R1L20"
WATTAGE"1/16W"
MATERIAL"CHIP"
TOLERANCE"1%"
PACK_TYPE"0402"
PART_NUMBER"G21796-066"
CDS_LIB"mstr_discrete"
CDS_LOCATION"R1L20"
ROOM"BMC_DEBUG_HEADER"
$SEC"1"
CDS_SEC"1"
BOM_COST"DEBUG";
"B"
$PN"2"19;
"A"
$PN"1"42;
%"RES"
"1","(-6900,3900)","0","mstr_discrete","I74";
;
PART_NUMBER"G21796-066"
TOLERANCE"1%"
VALUE"10.0"
WATTAGE"1/16W"
LOCATION"R1L18"
PACK_TYPE"0402"
MATERIAL"CHIP"
CDS_LOCATION"R1L18"
ROOM"BMC_DEBUG_HEADER"
BOM_COST"DEBUG"
CDS_LIB"mstr_discrete"
$SEC"1"
CDS_SEC"1";
"B"
$PN"2"36;
"A"
$PN"1"45;
%"RES"
"1","(-6900,3750)","0","mstr_discrete","I75";
;
MATERIAL"CHIP"
PACK_TYPE"0402"
VALUE"10.0"
TOLERANCE"1%"
PART_NUMBER"G21796-066"
WATTAGE"1/16W"
LOCATION"R1L14"
CDS_LOCATION"R1L14"
ROOM"BMC_DEBUG_HEADER"
$SEC"1"
CDS_SEC"1"
BOM_COST"DEBUG"
CDS_LIB"mstr_discrete";
"B"
$PN"2"37;
"A"
$PN"1"44;
%"RES"
"1","(-6900,3600)","0","mstr_discrete","I76";
;
MATERIAL"CHIP"
PART_NUMBER"G21796-066"
VALUE"10.0"
LOCATION"R1L11"
TOLERANCE"1%"
WATTAGE"1/16W"
PACK_TYPE"0402"
BOM_COST"DEBUG"
CDS_SEC"1"
$SEC"1"
CDS_LOCATION"R1L11"
ROOM"BMC_DEBUG_HEADER"
CDS_LIB"mstr_discrete";
"B"
$PN"2"40;
"A"
$PN"1"41;
%"RES"
"2","(-1450,1725)","0","mstr_discrete","I80";
;
CDS_SEC"1"
PACK_TYPE"0402"
PART_NUMBER"G21796-112"
MATERIAL"CHIP"
TOLERANCE"1%"
VALUE"2.21K"
WATTAGE"1/16W"
LOCATION"R9A7"
CDS_LIB"mstr_discrete"
SEC_TYPE"0402"
BOM_COST"DEBUG"
SEC"1"
CDS_LOCATION"R9A7"
ROOM"BMC_DEBUG_HEADER";
"A"
$PN"1"10;
"B"
$PN"2"13;
%"P3V3_STBY"
"1","(-1450,1975)","0","mstr_symbols","I81";
;
SIZE"1B"
BODY_TYPE"PLUMBING"
CDS_LIB"mstr_symbols"
VOLTAGE"3.3V"
HDL_POWER"P3V3_STBY";
"G\NAC"10;
END.
